# T6G (Grand Teton) — schematic netlist excerpt (pin names and nets, part order shuffled) for the footprints in the layout excerpt that follows; sources: Cadence DE-HDL packaged netlist, KiCad conversion of 04192023_DAF0TMB3IC0_F0TG_MB_C_brd_V02_OCP.brd

C6650  Q_CAP_DIFFBUS  DIFF BUS_0.22UF 6.3V 20% X6S  pkg C0201  page 319 : \1\ = P5E_CPU1_P0_TX_BUF_C_DN<10> ; \2\ = P5E_CPU1_P0_TX_BUF_DN<10>

U104  74LVC1G07GV  IC  pkg SC-74A_2-9X1-5  page 133
  NC1  = NC_U104_NC1
  A  = FM_SYS_THROTTLE_N
  GND  = GND
  Y  = OCP_SFF_PWRBRK_BUFF_N
  VCC  = P3V3_AUX

R6063  Q_RES  33 5% CHIP  pkg 0402LF  page 155 : A = IRQ_OCP_V3_2_WAKE_BUF_N ; B = IRQ_LVC3_WAKE_N

(kicad_pcb
	(version 20260206)
	(generator "pcbnew")
	(generator_version "10.0")
	(general
		(thickness 1.6)
		(legacy_teardrops no)
	)
	(paper "A4")
	(title_block
		(title "04192023_DAF0TMB3IC0_F0TG_MB_C_brd_V02_OCP.brd")
		(comment 1 "Grand Teton / footprints 2973-2975 of 8354")
	)
	(layers
		(0 "F.Cu" signal "TOP")
		(4 "In1.Cu" signal "GND")
		(6 "In2.Cu" signal "IN1")
		(8 "In3.Cu" signal "GND1")
		(10 "In4.Cu" signal "IN2")
		(12 "In5.Cu" signal "GND2")
		(14 "In6.Cu" signal "IN3")
		(16 "In7.Cu" signal "GND3")
		(18 "In8.Cu" signal "VCC")
		(20 "In9.Cu" signal "VCC1")
		(22 "In10.Cu" signal "GND4")
		(24 "In11.Cu" signal "IN4")
		(26 "In12.Cu" signal "GND5")
		(28 "In13.Cu" signal "IN5")
		(30 "In14.Cu" signal "GND6")
		(32 "In15.Cu" signal "IN6")
		(34 "In16.Cu" signal "GND7")
		(2 "B.Cu" signal "BOTTOM")
		(9 "F.Adhes" user "F.Adhesive")
		(11 "B.Adhes" user "B.Adhesive")
		(13 "F.Paste" user "Package Geometry/Pastemask Top")
		(15 "B.Paste" user "Package Geometry/Pastemask Bottom")
		(5 "F.SilkS" user "Ref Des/Silkscreen Top")
		(7 "B.SilkS" user "Ref Des/Silkscreen Bottom")
		(1 "F.Mask" user "Board Geometry/Soldermask Top")
		(3 "B.Mask" user "Board Geometry/Soldermask Bottom")
		(17 "Dwgs.User" user "User.Drawings")
		(19 "Cmts.User" user "User.Comments")
		(21 "Eco1.User" user "User.Eco1")
		(23 "Eco2.User" user "User.Eco2")
		(25 "Edge.Cuts" user "Board Geometry/Outline")
		(27 "Margin" user)
		(31 "F.CrtYd" user "Package Geometry/Place Bound Top")
		(29 "B.CrtYd" user "Package Geometry/Place Bound Bottom")
		(35 "F.Fab" user "Ref Des/Assembly Top")
		(33 "B.Fab" user "Ref Des/Assembly Bottom")
	)
	(footprint ""
		(layer "F.Cu")
		(at 78.401164 -408.517344 -90)
		(property "Reference" "C6650"
			(at 0 0 270)
			(layer "F.SilkS")
			(hide yes)
			(effects
				(font
					(size 1.27 1.27)
				)
			)
		)
		(property "Value" ""
			(at 0 0 270)
			(layer "F.Fab")
			(effects
				(font
					(size 1.27 1.27)
				)
			)
		)
		(duplicate_pad_numbers_are_jumpers no)
		(fp_line
			(start -0.299974 0.150114)
			(end -0.299974 -0.150114)
			(stroke
				(width 0.1)
				(type default)
			)
			(layer "F.Fab")
		)
		(fp_line
			(start 0.299974 0.150114)
			(end -0.299974 0.150114)
			(stroke
				(width 0.1)
				(type default)
			)
			(layer "F.Fab")
		)
		(fp_line
			(start -0.299974 -0.150114)
			(end 0.299974 -0.150114)
			(stroke
				(width 0.1)
				(type default)
			)
			(layer "F.Fab")
		)
		(fp_line
			(start 0.299974 -0.150114)
			(end 0.299974 0.150114)
			(stroke
				(width 0.1)
				(type default)
			)
			(layer "F.Fab")
		)
		(pad "1" smd rect
			(at -0.2667 0 270)
			(size 0.3048 0.381)
			(layers "F.Cu" "F.Mask" "F.Paste")
			(net "P5E_CPU1_P0_TX_BUF_C_DN<10>")
		)
		(pad "2" smd rect
			(at 0.2667 0 270)
			(size 0.3048 0.381)
			(layers "F.Cu" "F.Mask" "F.Paste")
			(net "P5E_CPU1_P0_TX_BUF_DN<10>")
		)
	)
	(footprint ""
		(layer "F.Cu")
		(at 368.324384 -14.394942)
		(property "Reference" "U104"
			(at -1.8034 -2.301748 0)
			(unlocked yes)
			(layer "F.SilkS")
			(effects
				(font
					(size 0.7874 0.5842)
					(thickness 0.1524)
				)
				(justify left)
			)
		)
		(property "Value" ""
			(at 0 0 0)
			(layer "F.Fab")
			(effects
				(font
					(size 1.27 1.27)
				)
			)
		)
		(duplicate_pad_numbers_are_jumpers no)
		(fp_line
			(start -1.733296 -1.549908)
			(end -1.733296 1.549908)
			(stroke
				(width 0.1524)
				(type default)
			)
			(layer "F.SilkS")
		)
		(fp_line
			(start -1.733296 1.549908)
			(end 1.733296 1.549908)
			(stroke
				(width 0.1524)
				(type default)
			)
			(layer "F.SilkS")
		)
		(fp_line
			(start -0.660908 -1.549908)
			(end -1.733296 -1.549908)
			(stroke
				(width 0.1524)
				(type default)
			)
			(layer "F.SilkS")
		)
		(fp_line
			(start 0 -0.889)
			(end -0.660908 -1.549908)
			(stroke
				(width 0.1524)
				(type default)
			)
			(layer "F.SilkS")
		)
		(fp_line
			(start 0.660908 -1.549908)
			(end 0 -0.889)
			(stroke
				(width 0.1524)
				(type default)
			)
			(layer "F.SilkS")
		)
		(fp_line
			(start 1.733296 -1.549908)
			(end 0.660908 -1.549908)
			(stroke
				(width 0.1524)
				(type default)
			)
			(layer "F.SilkS")
		)
		(fp_line
			(start 1.733296 1.549908)
			(end 1.733296 -1.549908)
			(stroke
				(width 0.1524)
				(type default)
			)
			(layer "F.SilkS")
		)
		(fp_poly
			(pts
				(xy -1.927606 -0.774954) (xy -2.419096 -0.49022) (xy -2.450338 -0.997204)
			)
			(stroke
				(width 0)
				(type default)
			)
			(fill yes)
			(layer "F.SilkS")
		)
		(fp_line
			(start -0.849884 -1.549908)
			(end -0.849884 1.549908)
			(stroke
				(width 0.1)
				(type default)
			)
			(layer "F.Fab")
		)
		(fp_line
			(start -0.849884 1.549908)
			(end 0.849884 1.549908)
			(stroke
				(width 0.1)
				(type default)
			)
			(layer "F.Fab")
		)
		(fp_line
			(start 0.849884 -1.549908)
			(end -0.849884 -1.549908)
			(stroke
				(width 0.1)
				(type default)
			)
			(layer "F.Fab")
		)
		(fp_line
			(start 0.849884 1.549908)
			(end 0.849884 -1.549908)
			(stroke
				(width 0.1)
				(type default)
			)
			(layer "F.Fab")
		)
		(fp_poly
			(pts
				(xy -2.4384 -1.20396) (xy -2.4384 -0.69596) (xy -1.9304 -0.94996)
			)
			(stroke
				(width 0)
				(type default)
			)
			(fill yes)
			(layer "F.Fab")
		)
		(pad "1" smd rect
			(at -1.199896 -0.94996 270)
			(size 0.5588 0.8128)
			(layers "F.Cu" "F.Mask" "F.Paste")
			(net "NC_U104_NC1")
		)
		(pad "2" smd rect
			(at -1.199896 0 270)
			(size 0.5588 0.8128)
			(layers "F.Cu" "F.Mask" "F.Paste")
			(net "FM_SYS_THROTTLE_N")
		)
		(pad "3" smd rect
			(at -1.199896 0.94996 270)
			(size 0.5588 0.8128)
			(layers "F.Cu" "F.Mask" "F.Paste")
			(net "GND")
		)
		(pad "4" smd rect
			(at 1.199896 0.94996 270)
			(size 0.5588 0.8128)
			(layers "F.Cu" "F.Mask" "F.Paste")
			(net "OCP_SFF_PWRBRK_BUFF_N")
		)
		(pad "5" smd rect
			(at 1.199896 -0.94996 270)
			(size 0.5588 0.8128)
			(layers "F.Cu" "F.Mask" "F.Paste")
			(net "P3V3_AUX")
		)
	)
	(footprint ""
		(layer "F.Cu")
		(at 157.15107 -74.75347 90)
		(property "Reference" "R6063"
			(at 0 0 90)
			(layer "F.SilkS")
			(hide yes)
			(effects
				(font
					(size 1.27 1.27)
				)
			)
		)
		(property "Value" ""
			(at 0 0 90)
			(layer "F.Fab")
			(effects
				(font
					(size 1.27 1.27)
				)
			)
		)
		(duplicate_pad_numbers_are_jumpers no)
		(fp_line
			(start 0.7874 -0.4064)
			(end 0.7874 0.4064)
			(stroke
				(width 0.1524)
				(type default)
			)
			(layer "F.SilkS")
		)
		(fp_line
			(start -0.7874 -0.4064)
			(end 0.7874 -0.4064)
			(stroke
				(width 0.1524)
				(type default)
			)
			(layer "F.SilkS")
		)
		(fp_line
			(start 0.7874 0.4064)
			(end -0.7874 0.4064)
			(stroke
				(width 0.1524)
				(type default)
			)
			(layer "F.SilkS")
		)
		(fp_line
			(start -0.7874 0.4064)
			(end -0.7874 -0.4064)
			(stroke
				(width 0.1524)
				(type default)
			)
			(layer "F.SilkS")
		)
		(fp_line
			(start -0.12065 -0.305054)
			(end -0.12065 -0.2794)
			(stroke
				(width 0.1)
				(type default)
			)
			(layer "F.Fab")
		)
		(fp_line
			(start -0.67945 -0.305054)
			(end -0.12065 -0.305054)
			(stroke
				(width 0.1)
				(type default)
			)
			(layer "F.Fab")
		)
		(fp_line
			(start 0.67945 -0.3048)
			(end 0.67945 0.3048)
			(stroke
				(width 0.1)
				(type default)
			)
			(layer "F.Fab")
		)
		(fp_line
			(start 0.12065 -0.3048)
			(end 0.67945 -0.3048)
			(stroke
				(width 0.1)
				(type default)
			)
			(layer "F.Fab")
		)
		(fp_line
			(start 0.12065 -0.2794)
			(end 0.12065 -0.3048)
			(stroke
				(width 0.1)
				(type default)
			)
			(layer "F.Fab")
		)
		(fp_line
			(start -0.12065 -0.2794)
			(end 0.12065 -0.2794)
			(stroke
				(width 0.1)
				(type default)
			)
			(layer "F.Fab")
		)
		(fp_line
			(start 0.120396 0.2794)
			(end -0.12065 0.2794)
			(stroke
				(width 0.1)
				(type default)
			)
			(layer "F.Fab")
		)
		(fp_line
			(start -0.12065 0.2794)
			(end -0.12065 0.3048)
			(stroke
				(width 0.1)
				(type default)
			)
			(layer "F.Fab")
		)
		(fp_line
			(start 0.67945 0.3048)
			(end 0.120396 0.3048)
			(stroke
				(width 0.1)
				(type default)
			)
			(layer "F.Fab")
		)
		(fp_line
			(start 0.120396 0.3048)
			(end 0.120396 0.2794)
			(stroke
				(width 0.1)
				(type default)
			)
			(layer "F.Fab")
		)
		(fp_line
			(start -0.12065 0.3048)
			(end -0.67945 0.3048)
			(stroke
				(width 0.1)
				(type default)
			)
			(layer "F.Fab")
		)
		(fp_line
			(start -0.67945 0.3048)
			(end -0.67945 -0.305054)
			(stroke
				(width 0.1)
				(type default)
			)
			(layer "F.Fab")
		)
		(pad "1" smd circle
			(at -0.40005 0 90)
			(size 0 0)
			(layers "F.Cu" "F.Mask" "F.Paste")
			(net "IRQ_OCP_V3_2_WAKE_BUF_N")
		)
		(pad "2" smd circle
			(at 0.40005 0 90)
			(size 0 0)
			(layers "F.Cu" "F.Mask" "F.Paste")
			(net "IRQ_LVC3_WAKE_N")
		)
	)
)
